(kicad_pcb
	(version 20260206)
	(generator "pcbnew")
	(generator_version "10.0")
	(general
		(thickness 1.6)
		(legacy_teardrops no)
	)
	(paper "A4")
	(title_block
		(title "peb — Lightning_PEB_BRD.brd")
		(comment 1 "Lightning (Wiwynn / Facebook NVMe JBOF) / footprints 2131-2137 of 2563")
	)
	(layers
		(0 "F.Cu" signal "TOP")
		(4 "In1.Cu" signal "L2GND")
		(6 "In2.Cu" signal "L3")
		(8 "In3.Cu" signal "L4VCC")
		(10 "In4.Cu" signal "L5VCC")
		(12 "In5.Cu" signal "L6")
		(14 "In6.Cu" signal "L7GND")
		(2 "B.Cu" signal "BOTTOM")
		(9 "F.Adhes" user "F.Adhesive")
		(11 "B.Adhes" user "B.Adhesive")
		(13 "F.Paste" user "Package Geometry/Pastemask Top")
		(15 "B.Paste" user "Package Geometry/Pastemask Bottom")
		(5 "F.SilkS" user "Ref Des/Silkscreen Top")
		(7 "B.SilkS" user "Ref Des/Silkscreen Bottom")
		(1 "F.Mask" user "Board Geometry/Soldermask Top")
		(3 "B.Mask" user "Board Geometry/Soldermask Bottom")
		(17 "Dwgs.User" user "User.Drawings")
		(19 "Cmts.User" user "User.Comments")
		(21 "Eco1.User" user "User.Eco1")
		(23 "Eco2.User" user "User.Eco2")
		(25 "Edge.Cuts" user "Board Geometry/Outline")
		(27 "Margin" user)
		(31 "F.CrtYd" user "Package Geometry/Place Bound Top")
		(29 "B.CrtYd" user "Package Geometry/Place Bound Bottom")
		(35 "F.Fab" user "Ref Des/Assembly Top")
		(33 "B.Fab" user "Ref Des/Assembly Bottom")
	)
	(footprint ""
		(layer "B.Cu")
		(at 241.1476 -11.2014 -90)
		(property "Reference" "R41"
			(at 0 0 90)
			(layer "B.SilkS")
			(hide yes)
			(effects
				(font
					(size 1.27 1.27)
				)
				(justify mirror)
			)
		)
		(property "Value" "1KR3F-GP"
			(at 0.0254 -2.5146 270)
			(unlocked yes)
			(layer "B.Fab")
			(hide yes)
			(effects
				(font
					(size 1.016 1.016)
					(thickness 0.1524)
				)
				(justify mirror)
			)
		)
		(property "Device Type" "R603H22"
			(at 0.0254 -4.0386 270)
			(unlocked yes)
			(layer "B.Fab")
			(hide yes)
			(effects
				(font
					(size 1.016 1.016)
					(thickness 0.1524)
				)
				(justify mirror)
			)
		)
		(duplicate_pad_numbers_are_jumpers no)
		(fp_line
			(start -0.2032 0)
			(end -0.4826 0)
			(stroke
				(width 0.2032)
				(type default)
			)
			(layer "B.SilkS")
		)
		(fp_line
			(start 0.4826 0)
			(end 0.2032 0)
			(stroke
				(width 0.2032)
				(type default)
			)
			(layer "B.SilkS")
		)
		(fp_rect
			(start 0.5842 1.3335)
			(end -0.5842 -1.3335)
			(stroke
				(width 0)
				(type default)
			)
			(fill no)
			(layer "B.CrtYd")
		)
		(fp_rect
			(start 0.5842 1.3335)
			(end -0.5842 -1.3335)
			(stroke
				(width 0)
				(type default)
			)
			(fill no)
			(layer "B.Fab")
		)
		(pad "1" smd custom
			(at 0 -0.762 90)
			(size 0.2159 0.2159)
			(layers "B.Cu" "B.Mask" "B.Paste")
			(net "DUT_VDDO")
			(options
				(clearance outline)
				(anchor circle)
			)
			(primitives
				(gr_poly
					(pts
						(arc
							(start -0.3302 0.4318)
							(mid -0.402042 0.402042)
							(end -0.4318 0.3302)
						)
						(arc
							(start -0.4318 -0.3302)
							(mid -0.402042 -0.402042)
							(end -0.3302 -0.4318)
						)
						(arc
							(start 0.3302 -0.4318)
							(mid 0.402042 -0.402042)
							(end 0.4318 -0.3302)
						)
						(arc
							(start 0.4318 0.3302)
							(mid 0.402042 0.402042)
							(end 0.3302 0.4318)
						)
					)
					(width 0)
					(fill yes)
				)
			)
		)
		(pad "2" smd custom
			(at 0 0.762 90)
			(size 0.2159 0.2159)
			(layers "B.Cu" "B.Mask" "B.Paste")
			(net "DUT_VDDO_REF")
			(options
				(clearance outline)
				(anchor circle)
			)
			(primitives
				(gr_poly
					(pts
						(arc
							(start -0.3302 0.4318)
							(mid -0.402042 0.402042)
							(end -0.4318 0.3302)
						)
						(arc
							(start -0.4318 -0.3302)
							(mid -0.402042 -0.402042)
							(end -0.3302 -0.4318)
						)
						(arc
							(start 0.3302 -0.4318)
							(mid 0.402042 -0.402042)
							(end 0.4318 -0.3302)
						)
						(arc
							(start 0.4318 0.3302)
							(mid 0.402042 0.402042)
							(end 0.3302 0.4318)
						)
					)
					(width 0)
					(fill yes)
				)
			)
		)
	)
	(footprint ""
		(layer "B.Cu")
		(at 238.252 -23.241 180)
		(property "Reference" "R782"
			(at 0 0 0)
			(layer "B.SilkS")
			(hide yes)
			(effects
				(font
					(size 1.27 1.27)
				)
				(justify mirror)
			)
		)
		(property "Value" "4K7R2F-GP"
			(at -0.064008 -3.993896 180)
			(unlocked yes)
			(layer "B.Fab")
			(hide yes)
			(effects
				(font
					(size 1.016 1.016)
					(thickness 0.1524)
				)
				(justify mirror)
			)
		)
		(property "Device Type" "R402H16"
			(at -0.064008 -5.517896 180)
			(unlocked yes)
			(layer "B.Fab")
			(hide yes)
			(effects
				(font
					(size 1.016 1.016)
					(thickness 0.1524)
				)
				(justify mirror)
			)
		)
		(duplicate_pad_numbers_are_jumpers no)
		(fp_line
			(start 0.508 -0.9398)
			(end 0.508 0.9398)
			(stroke
				(width 0.1524)
				(type default)
			)
			(layer "B.SilkS")
		)
		(fp_line
			(start -0.508 -0.9398)
			(end 0.508 -0.9398)
			(stroke
				(width 0.1524)
				(type default)
			)
			(layer "B.SilkS")
		)
		(fp_rect
			(start 0.508 0.9398)
			(end -0.508 -0.9398)
			(stroke
				(width 0)
				(type default)
			)
			(fill no)
			(layer "B.CrtYd")
		)
		(fp_rect
			(start 0.508 0.9398)
			(end -0.508 -0.9398)
			(stroke
				(width 0)
				(type default)
			)
			(fill no)
			(layer "B.Fab")
		)
		(pad "1" smd custom
			(at 0 -0.4445)
			(size 0.1397 0.1397)
			(layers "B.Cu" "B.Mask" "B.Paste")
			(net "BOOTSTRAP2")
			(options
				(clearance outline)
				(anchor circle)
			)
			(primitives
				(gr_poly
					(pts
						(arc
							(start -0.1778 0.2794)
							(mid -0.249642 0.249642)
							(end -0.2794 0.1778)
						)
						(arc
							(start -0.2794 -0.1778)
							(mid -0.249642 -0.249642)
							(end -0.1778 -0.2794)
						)
						(arc
							(start 0.1778 -0.2794)
							(mid 0.249642 -0.249642)
							(end 0.2794 -0.1778)
						)
						(arc
							(start 0.2794 0.1778)
							(mid 0.249642 0.249642)
							(end 0.1778 0.2794)
						)
					)
					(width 0)
					(fill yes)
				)
			)
		)
		(pad "2" smd custom
			(at 0 0.4445)
			(size 0.1397 0.1397)
			(layers "B.Cu" "B.Mask" "B.Paste")
			(net "BOOTSTRAP_R_2")
			(options
				(clearance outline)
				(anchor circle)
			)
			(primitives
				(gr_poly
					(pts
						(arc
							(start -0.1778 0.2794)
							(mid -0.249642 0.249642)
							(end -0.2794 0.1778)
						)
						(arc
							(start -0.2794 -0.1778)
							(mid -0.249642 -0.249642)
							(end -0.1778 -0.2794)
						)
						(arc
							(start 0.1778 -0.2794)
							(mid 0.249642 -0.249642)
							(end 0.2794 -0.1778)
						)
						(arc
							(start 0.2794 0.1778)
							(mid 0.249642 0.249642)
							(end 0.1778 0.2794)
						)
					)
					(width 0)
					(fill yes)
				)
			)
		)
	)
	(footprint ""
		(layer "B.Cu")
		(at 23.941786 -130.446018 90)
		(property "Reference" "R349"
			(at 0 0 90)
			(layer "B.SilkS")
			(hide yes)
			(effects
				(font
					(size 1.27 1.27)
				)
				(justify mirror)
			)
		)
		(property "Value" "3K3R2F-2-GP"
			(at -0.064008 -3.993896 90)
			(unlocked yes)
			(layer "B.Fab")
			(hide yes)
			(effects
				(font
					(size 1.016 1.016)
					(thickness 0.1524)
				)
				(justify mirror)
			)
		)
		(property "Device Type" "R402H16"
			(at -0.064008 -5.517896 90)
			(unlocked yes)
			(layer "B.Fab")
			(hide yes)
			(effects
				(font
					(size 1.016 1.016)
					(thickness 0.1524)
				)
				(justify mirror)
			)
		)
		(duplicate_pad_numbers_are_jumpers no)
		(fp_line
			(start 0.508 -0.9398)
			(end 0.508 0.9398)
			(stroke
				(width 0.1524)
				(type default)
			)
			(layer "B.SilkS")
		)
		(fp_line
			(start -0.508 -0.9398)
			(end 0.508 -0.9398)
			(stroke
				(width 0.1524)
				(type default)
			)
			(layer "B.SilkS")
		)
		(fp_rect
			(start 0.508 0.9398)
			(end -0.508 -0.9398)
			(stroke
				(width 0)
				(type default)
			)
			(fill no)
			(layer "B.CrtYd")
		)
		(fp_rect
			(start 0.508 0.9398)
			(end -0.508 -0.9398)
			(stroke
				(width 0)
				(type default)
			)
			(fill no)
			(layer "B.Fab")
		)
		(pad "1" smd custom
			(at 0 -0.4445 270)
			(size 0.1397 0.1397)
			(layers "B.Cu" "B.Mask" "B.Paste")
			(net "P3V3_STBY")
			(options
				(clearance outline)
				(anchor circle)
			)
			(primitives
				(gr_poly
					(pts
						(arc
							(start -0.1778 0.2794)
							(mid -0.249642 0.249642)
							(end -0.2794 0.1778)
						)
						(arc
							(start -0.2794 -0.1778)
							(mid -0.249642 -0.249642)
							(end -0.1778 -0.2794)
						)
						(arc
							(start 0.1778 -0.2794)
							(mid 0.249642 -0.249642)
							(end 0.2794 -0.1778)
						)
						(arc
							(start 0.2794 0.1778)
							(mid 0.249642 0.249642)
							(end 0.1778 0.2794)
						)
					)
					(width 0)
					(fill yes)
				)
			)
		)
		(pad "2" smd custom
			(at 0 0.4445 270)
			(size 0.1397 0.1397)
			(layers "B.Cu" "B.Mask" "B.Paste")
			(net "ROMA18")
			(options
				(clearance outline)
				(anchor circle)
			)
			(primitives
				(gr_poly
					(pts
						(arc
							(start -0.1778 0.2794)
							(mid -0.249642 0.249642)
							(end -0.2794 0.1778)
						)
						(arc
							(start -0.2794 -0.1778)
							(mid -0.249642 -0.249642)
							(end -0.1778 -0.2794)
						)
						(arc
							(start 0.1778 -0.2794)
							(mid 0.249642 -0.249642)
							(end 0.2794 -0.1778)
						)
						(arc
							(start 0.2794 0.1778)
							(mid 0.249642 0.249642)
							(end 0.1778 0.2794)
						)
					)
					(width 0)
					(fill yes)
				)
			)
		)
	)
	(footprint ""
		(layer "B.Cu")
		(at 310.007 -61.595 180)
		(property "Reference" "PG62"
			(at 0 0 0)
			(layer "B.SilkS")
			(hide yes)
			(effects
				(font
					(size 1.27 1.27)
				)
				(justify mirror)
			)
		)
		(property "Value" "GAP-CLOSE-PWR-3-GP"
			(at -0.0254 -6.5786 180)
			(unlocked yes)
			(layer "B.Fab")
			(hide yes)
			(effects
				(font
					(size 1.016 1.016)
					(thickness 0.1524)
				)
				(justify mirror)
			)
		)
		(property "Device Type" "GAP-CLOSE-PWR-3"
			(at -0.0254 -8.255 180)
			(unlocked yes)
			(layer "B.Fab")
			(hide yes)
			(effects
				(font
					(size 1.016 1.016)
					(thickness 0.1524)
				)
				(justify mirror)
			)
		)
		(duplicate_pad_numbers_are_jumpers no)
		(fp_rect
			(start 0.7112 0.4572)
			(end -0.7112 -0.4572)
			(stroke
				(width 0)
				(type default)
			)
			(fill no)
			(layer "B.CrtYd")
		)
		(fp_poly
			(pts
				(xy 0.7112 -0.4572) (xy -0.7112 -0.4572) (xy -0.7112 0.4572) (xy 0.7112 0.4572)
			)
			(stroke
				(width 0)
				(type default)
			)
			(fill no)
			(layer "B.Fab")
		)
		(pad "1" smd rect
			(at 0.3048 0)
			(size 0.6604 0.762)
			(layers "B.Cu" "B.Mask" "B.Paste")
			(net "DUT_VDD")
		)
		(pad "2" smd rect
			(at -0.3048 0)
			(size 0.6604 0.762)
			(layers "B.Cu" "B.Mask" "B.Paste")
			(net "P0V9_E")
		)
	)
	(footprint ""
		(layer "B.Cu")
		(at 271.018 -5.207 90)
		(property "Reference" "R2975"
			(at 0 0 90)
			(layer "B.SilkS")
			(hide yes)
			(effects
				(font
					(size 1.27 1.27)
				)
				(justify mirror)
			)
		)
		(property "Value" "0R2J-2-GP"
			(at -0.064008 -3.993896 90)
			(unlocked yes)
			(layer "B.Fab")
			(hide yes)
			(effects
				(font
					(size 1.016 1.016)
					(thickness 0.1524)
				)
				(justify mirror)
			)
		)
		(property "Device Type" "R402H16"
			(at -0.064008 -5.517896 90)
			(unlocked yes)
			(layer "B.Fab")
			(hide yes)
			(effects
				(font
					(size 1.016 1.016)
					(thickness 0.1524)
				)
				(justify mirror)
			)
		)
		(duplicate_pad_numbers_are_jumpers no)
		(fp_line
			(start 0.508 -0.9398)
			(end 0.508 0.9398)
			(stroke
				(width 0.1524)
				(type default)
			)
			(layer "B.SilkS")
		)
		(fp_line
			(start -0.508 -0.9398)
			(end 0.508 -0.9398)
			(stroke
				(width 0.1524)
				(type default)
			)
			(layer "B.SilkS")
		)
		(fp_rect
			(start 0.508 0.9398)
			(end -0.508 -0.9398)
			(stroke
				(width 0)
				(type default)
			)
			(fill no)
			(layer "B.CrtYd")
		)
		(fp_rect
			(start 0.508 0.9398)
			(end -0.508 -0.9398)
			(stroke
				(width 0)
				(type default)
			)
			(fill no)
			(layer "B.Fab")
		)
		(pad "1" smd custom
			(at 0 -0.4445 270)
			(size 0.1397 0.1397)
			(layers "B.Cu" "B.Mask" "B.Paste")
			(net "PCIE_REFCLK_H1_N")
			(options
				(clearance outline)
				(anchor circle)
			)
			(primitives
				(gr_poly
					(pts
						(arc
							(start -0.1778 0.2794)
							(mid -0.249642 0.249642)
							(end -0.2794 0.1778)
						)
						(arc
							(start -0.2794 -0.1778)
							(mid -0.249642 -0.249642)
							(end -0.1778 -0.2794)
						)
						(arc
							(start 0.1778 -0.2794)
							(mid 0.249642 -0.249642)
							(end 0.2794 -0.1778)
						)
						(arc
							(start 0.2794 0.1778)
							(mid 0.249642 0.249642)
							(end 0.1778 0.2794)
						)
					)
					(width 0)
					(fill yes)
				)
			)
		)
		(pad "2" smd custom
			(at 0 0.4445 270)
			(size 0.1397 0.1397)
			(layers "B.Cu" "B.Mask" "B.Paste")
			(net "PCIE_REFCLK_H1_N_R")
			(options
				(clearance outline)
				(anchor circle)
			)
			(primitives
				(gr_poly
					(pts
						(arc
							(start -0.1778 0.2794)
							(mid -0.249642 0.249642)
							(end -0.2794 0.1778)
						)
						(arc
							(start -0.2794 -0.1778)
							(mid -0.249642 -0.249642)
							(end -0.1778 -0.2794)
						)
						(arc
							(start 0.1778 -0.2794)
							(mid 0.249642 -0.249642)
							(end 0.2794 -0.1778)
						)
						(arc
							(start 0.2794 0.1778)
							(mid 0.249642 0.249642)
							(end 0.1778 0.2794)
						)
					)
					(width 0)
					(fill yes)
				)
			)
		)
	)
	(footprint ""
		(layer "B.Cu")
		(at 249.5804 -44.9961 90)
		(property "Reference" "C596"
			(at 0 0 90)
			(layer "B.SilkS")
			(hide yes)
			(effects
				(font
					(size 1.27 1.27)
				)
				(justify mirror)
			)
		)
		(property "Value" "SCD1U16V1KX-1-GP"
			(at 2.8321 -1.7399 90)
			(unlocked yes)
			(layer "B.Fab")
			(hide yes)
			(effects
				(font
					(size 1.016 1.016)
					(thickness 0.1524)
				)
				(justify mirror)
			)
		)
		(property "Device Type" "C0201H13"
			(at 2.8321 -3.2639 90)
			(unlocked yes)
			(layer "B.Fab")
			(hide yes)
			(effects
				(font
					(size 1.016 1.016)
					(thickness 0.1524)
				)
				(justify mirror)
			)
		)
		(duplicate_pad_numbers_are_jumpers no)
		(fp_rect
			(start 0.2794 0.6477)
			(end -0.2794 -0.6477)
			(stroke
				(width 0)
				(type default)
			)
			(fill no)
			(layer "B.CrtYd")
		)
		(fp_rect
			(start 0.2794 0.6477)
			(end -0.2794 -0.6477)
			(stroke
				(width 0)
				(type default)
			)
			(fill no)
			(layer "B.Fab")
		)
		(pad "1" smd custom
			(at 0 -0.2794 270)
			(size 0.0762 0.0762)
			(layers "B.Cu" "B.Mask" "B.Paste")
			(net "DUT_AVD_PCIE")
			(options
				(clearance outline)
				(anchor circle)
			)
			(primitives
				(gr_poly
					(pts
						(arc
							(start 0.1524 0.127)
							(mid 0.137521 0.162921)
							(end 0.1016 0.1778)
						)
						(arc
							(start -0.1016 0.1778)
							(mid -0.137521 0.162921)
							(end -0.1524 0.127)
						)
						(arc
							(start -0.1524 -0.127)
							(mid -0.137521 -0.162921)
							(end -0.1016 -0.1778)
						)
						(arc
							(start 0.1016 -0.1778)
							(mid 0.137521 -0.162921)
							(end 0.1524 -0.127)
						)
					)
					(width 0)
					(fill yes)
				)
			)
		)
		(pad "2" smd custom
			(at 0 0.2794 270)
			(size 0.0762 0.0762)
			(layers "B.Cu" "B.Mask" "B.Paste")
			(net "GND")
			(options
				(clearance outline)
				(anchor circle)
			)
			(primitives
				(gr_poly
					(pts
						(arc
							(start 0.1524 0.127)
							(mid 0.137521 0.162921)
							(end 0.1016 0.1778)
						)
						(arc
							(start -0.1016 0.1778)
							(mid -0.137521 0.162921)
							(end -0.1524 0.127)
						)
						(arc
							(start -0.1524 -0.127)
							(mid -0.137521 -0.162921)
							(end -0.1016 -0.1778)
						)
						(arc
							(start 0.1016 -0.1778)
							(mid 0.137521 -0.162921)
							(end 0.1524 -0.127)
						)
					)
					(width 0)
					(fill yes)
				)
			)
		)
	)
	(footprint ""
		(layer "B.Cu")
		(at 125.095 -205.74)
		(property "Reference" "R3222"
			(at 0 0 0)
			(layer "B.SilkS")
			(hide yes)
			(effects
				(font
					(size 1.27 1.27)
				)
				(justify mirror)
			)
		)
		(property "Value" "0R2J-2-GP"
			(at -0.064008 -3.993896 0)
			(unlocked yes)
			(layer "B.Fab")
			(hide yes)
			(effects
				(font
					(size 1.016 1.016)
					(thickness 0.1524)
				)
				(justify mirror)
			)
		)
		(property "Device Type" "R402H16"
			(at -0.064008 -5.517896 0)
			(unlocked yes)
			(layer "B.Fab")
			(hide yes)
			(effects
				(font
					(size 1.016 1.016)
					(thickness 0.1524)
				)
				(justify mirror)
			)
		)
		(duplicate_pad_numbers_are_jumpers no)
		(fp_line
			(start -0.508 -0.9398)
			(end 0.508 -0.9398)
			(stroke
				(width 0.1524)
				(type default)
			)
			(layer "B.SilkS")
		)
		(fp_line
			(start 0.508 -0.9398)
			(end 0.508 0.9398)
			(stroke
				(width 0.1524)
				(type default)
			)
			(layer "B.SilkS")
		)
		(fp_rect
			(start 0.508 0.9398)
			(end -0.508 -0.9398)
			(stroke
				(width 0)
				(type default)
			)
			(fill no)
			(layer "B.CrtYd")
		)
		(fp_rect
			(start 0.508 0.9398)
			(end -0.508 -0.9398)
			(stroke
				(width 0)
				(type default)
			)
			(fill no)
			(layer "B.Fab")
		)
		(pad "1" smd custom
			(at 0 -0.4445 180)
			(size 0.1397 0.1397)
			(layers "B.Cu" "B.Mask" "B.Paste")
			(net "SSD_PERST#7")
			(options
				(clearance outline)
				(anchor circle)
			)
			(primitives
				(gr_poly
					(pts
						(arc
							(start -0.1778 0.2794)
							(mid -0.249642 0.249642)
							(end -0.2794 0.1778)
						)
						(arc
							(start -0.2794 -0.1778)
							(mid -0.249642 -0.249642)
							(end -0.1778 -0.2794)
						)
						(arc
							(start 0.1778 -0.2794)
							(mid 0.249642 -0.249642)
							(end 0.2794 -0.1778)
						)
						(arc
							(start 0.2794 0.1778)
							(mid 0.249642 0.249642)
							(end 0.1778 0.2794)
						)
					)
					(width 0)
					(fill yes)
				)
			)
		)
		(pad "2" smd custom
			(at 0 0.4445 180)
			(size 0.1397 0.1397)
			(layers "B.Cu" "B.Mask" "B.Paste")
			(net "SSD_PERST#0_B7")
			(options
				(clearance outline)
				(anchor circle)
			)
			(primitives
				(gr_poly
					(pts
						(arc
							(start -0.1778 0.2794)
							(mid -0.249642 0.249642)
							(end -0.2794 0.1778)
						)
						(arc
							(start -0.2794 -0.1778)
							(mid -0.249642 -0.249642)
							(end -0.1778 -0.2794)
						)
						(arc
							(start 0.1778 -0.2794)
							(mid 0.249642 -0.249642)
							(end 0.2794 -0.1778)
						)
						(arc
							(start 0.2794 0.1778)
							(mid 0.249642 0.249642)
							(end 0.1778 0.2794)
						)
					)
					(width 0)
					(fill yes)
				)
			)
		)
	)
)
